# S9S_MB_2U (Grand Teton) — schematic netlist excerpt (pin names and nets, part order shuffled) for the footprints in the layout excerpt that follows; sources: Cadence DE-HDL packaged netlist, KiCad conversion of 03242023_DA0F0TMBIJ0_F0T_Motherboard_J_brd_V01_OCP.brd

R1000  Q_RES  4.7K 5% CHIP  pkg 0402LF  page 235 : A = P3V3 ; B = FM_SMB_PEHPCPU0_PCIE_ALERT_R_N
PC281_P0_3  Q_CAP  22UF 16V 20% X6S  pkg C0805  page 268 : A = SW_P12V_PVCCIN_CPU0_FLT ; B = GND
R74  Q_RES  84.5K 1% CHIP  pkg 0402LF  page 111 : A = PD_CHG_CPU1_DIMM2_SAA ; B = GND

(kicad_pcb
	(version 20260206)
	(generator "pcbnew")
	(generator_version "10.0")
	(general
		(thickness 1.6)
		(legacy_teardrops no)
	)
	(paper "A4")
	(title_block
		(title "03242023_DA0F0TMBIJ0_F0T_Motherboard_J_brd_V01_OCP.brd")
		(comment 1 "Grand Teton / footprints 4321-4323 of 6105")
	)
	(layers
		(0 "F.Cu" signal "TOP")
		(4 "In1.Cu" signal "GND")
		(6 "In2.Cu" signal "IN1")
		(8 "In3.Cu" signal "GND1")
		(10 "In4.Cu" signal "IN2")
		(12 "In5.Cu" signal "GND2")
		(14 "In6.Cu" signal "IN3")
		(16 "In7.Cu" signal "GND3")
		(18 "In8.Cu" signal "VCC")
		(20 "In9.Cu" signal "VCC1")
		(22 "In10.Cu" signal "GND4")
		(24 "In11.Cu" signal "IN4")
		(26 "In12.Cu" signal "GND5")
		(28 "In13.Cu" signal "IN5")
		(30 "In14.Cu" signal "GND6")
		(32 "In15.Cu" signal "IN6")
		(34 "In16.Cu" signal "GND7")
		(2 "B.Cu" signal "BOTTOM")
		(9 "F.Adhes" user "F.Adhesive")
		(11 "B.Adhes" user "B.Adhesive")
		(13 "F.Paste" user "Package Geometry/Pastemask Top")
		(15 "B.Paste" user "Package Geometry/Pastemask Bottom")
		(5 "F.SilkS" user "Ref Des/Silkscreen Top")
		(7 "B.SilkS" user "Ref Des/Silkscreen Bottom")
		(1 "F.Mask" user "Board Geometry/Soldermask Top")
		(3 "B.Mask" user "Board Geometry/Soldermask Bottom")
		(17 "Dwgs.User" user "User.Drawings")
		(19 "Cmts.User" user "User.Comments")
		(21 "Eco1.User" user "User.Eco1")
		(23 "Eco2.User" user "User.Eco2")
		(25 "Edge.Cuts" user "Board Geometry/Outline")
		(27 "Margin" user)
		(31 "F.CrtYd" user "Package Geometry/Place Bound Top")
		(29 "B.CrtYd" user "Package Geometry/Place Bound Bottom")
		(35 "F.Fab" user "Ref Des/Assembly Top")
		(33 "B.Fab" user "Ref Des/Assembly Bottom")
	)
	(footprint ""
		(layer "B.Cu")
		(at 191.04864 -319.217548)
		(property "Reference" "R74"
			(at 0 0 0)
			(layer "B.SilkS")
			(hide yes)
			(effects
				(font
					(size 1.27 1.27)
				)
				(justify mirror)
			)
		)
		(property "Value" ""
			(at 0 0 0)
			(layer "B.Fab")
			(effects
				(font
					(size 1.27 1.27)
				)
				(justify mirror)
			)
		)
		(duplicate_pad_numbers_are_jumpers no)
		(fp_line
			(start -0.7874 -0.4064)
			(end -0.7874 0.4064)
			(stroke
				(width 0.1524)
				(type default)
			)
			(layer "B.SilkS")
		)
		(fp_line
			(start -0.7874 0.4064)
			(end 0.7874 0.4064)
			(stroke
				(width 0.1524)
				(type default)
			)
			(layer "B.SilkS")
		)
		(fp_line
			(start 0.7874 -0.4064)
			(end -0.7874 -0.4064)
			(stroke
				(width 0.1524)
				(type default)
			)
			(layer "B.SilkS")
		)
		(fp_line
			(start 0.7874 0.4064)
			(end 0.7874 -0.4064)
			(stroke
				(width 0.1524)
				(type default)
			)
			(layer "B.SilkS")
		)
		(fp_line
			(start -0.67945 -0.3048)
			(end -0.67945 0.3048)
			(stroke
				(width 0.1)
				(type default)
			)
			(layer "B.Fab")
		)
		(fp_line
			(start -0.67945 0.3048)
			(end -0.120396 0.3048)
			(stroke
				(width 0.1)
				(type default)
			)
			(layer "B.Fab")
		)
		(fp_line
			(start -0.12065 -0.3048)
			(end -0.67945 -0.3048)
			(stroke
				(width 0.1)
				(type default)
			)
			(layer "B.Fab")
		)
		(fp_line
			(start -0.12065 -0.2794)
			(end -0.12065 -0.3048)
			(stroke
				(width 0.1)
				(type default)
			)
			(layer "B.Fab")
		)
		(fp_line
			(start -0.120396 0.2794)
			(end 0.12065 0.2794)
			(stroke
				(width 0.1)
				(type default)
			)
			(layer "B.Fab")
		)
		(fp_line
			(start -0.120396 0.3048)
			(end -0.120396 0.2794)
			(stroke
				(width 0.1)
				(type default)
			)
			(layer "B.Fab")
		)
		(fp_line
			(start 0.12065 -0.305054)
			(end 0.12065 -0.2794)
			(stroke
				(width 0.1)
				(type default)
			)
			(layer "B.Fab")
		)
		(fp_line
			(start 0.12065 -0.2794)
			(end -0.12065 -0.2794)
			(stroke
				(width 0.1)
				(type default)
			)
			(layer "B.Fab")
		)
		(fp_line
			(start 0.12065 0.2794)
			(end 0.12065 0.3048)
			(stroke
				(width 0.1)
				(type default)
			)
			(layer "B.Fab")
		)
		(fp_line
			(start 0.12065 0.3048)
			(end 0.67945 0.3048)
			(stroke
				(width 0.1)
				(type default)
			)
			(layer "B.Fab")
		)
		(fp_line
			(start 0.67945 -0.305054)
			(end 0.12065 -0.305054)
			(stroke
				(width 0.1)
				(type default)
			)
			(layer "B.Fab")
		)
		(fp_line
			(start 0.67945 0.3048)
			(end 0.67945 -0.305054)
			(stroke
				(width 0.1)
				(type default)
			)
			(layer "B.Fab")
		)
		(pad "1" smd circle
			(at 0.40005 0 180)
			(size 0 0)
			(layers "B.Cu" "B.Mask" "B.Paste")
			(net "PD_CHG_CPU1_DIMM2_SAA")
		)
		(pad "2" smd circle
			(at -0.40005 0 180)
			(size 0 0)
			(layers "B.Cu" "B.Mask" "B.Paste")
			(net "GND")
		)
	)
	(footprint ""
		(layer "B.Cu")
		(at 362.736638 -182.33771 180)
		(property "Reference" "R1000"
			(at 0 0 0)
			(layer "B.SilkS")
			(hide yes)
			(effects
				(font
					(size 1.27 1.27)
				)
				(justify mirror)
			)
		)
		(property "Value" ""
			(at 0 0 0)
			(layer "B.Fab")
			(effects
				(font
					(size 1.27 1.27)
				)
				(justify mirror)
			)
		)
		(duplicate_pad_numbers_are_jumpers no)
		(fp_line
			(start 0.7874 0.4064)
			(end 0.7874 -0.4064)
			(stroke
				(width 0.1524)
				(type default)
			)
			(layer "B.SilkS")
		)
		(fp_line
			(start 0.7874 -0.4064)
			(end -0.7874 -0.4064)
			(stroke
				(width 0.1524)
				(type default)
			)
			(layer "B.SilkS")
		)
		(fp_line
			(start -0.7874 0.4064)
			(end 0.7874 0.4064)
			(stroke
				(width 0.1524)
				(type default)
			)
			(layer "B.SilkS")
		)
		(fp_line
			(start -0.7874 -0.4064)
			(end -0.7874 0.4064)
			(stroke
				(width 0.1524)
				(type default)
			)
			(layer "B.SilkS")
		)
		(fp_line
			(start 0.67945 0.3048)
			(end 0.67945 -0.305054)
			(stroke
				(width 0.1)
				(type default)
			)
			(layer "B.Fab")
		)
		(fp_line
			(start 0.67945 -0.305054)
			(end 0.12065 -0.305054)
			(stroke
				(width 0.1)
				(type default)
			)
			(layer "B.Fab")
		)
		(fp_line
			(start 0.12065 0.3048)
			(end 0.67945 0.3048)
			(stroke
				(width 0.1)
				(type default)
			)
			(layer "B.Fab")
		)
		(fp_line
			(start 0.12065 0.2794)
			(end 0.12065 0.3048)
			(stroke
				(width 0.1)
				(type default)
			)
			(layer "B.Fab")
		)
		(fp_line
			(start 0.12065 -0.2794)
			(end -0.12065 -0.2794)
			(stroke
				(width 0.1)
				(type default)
			)
			(layer "B.Fab")
		)
		(fp_line
			(start 0.12065 -0.305054)
			(end 0.12065 -0.2794)
			(stroke
				(width 0.1)
				(type default)
			)
			(layer "B.Fab")
		)
		(fp_line
			(start -0.120396 0.3048)
			(end -0.120396 0.2794)
			(stroke
				(width 0.1)
				(type default)
			)
			(layer "B.Fab")
		)
		(fp_line
			(start -0.120396 0.2794)
			(end 0.12065 0.2794)
			(stroke
				(width 0.1)
				(type default)
			)
			(layer "B.Fab")
		)
		(fp_line
			(start -0.12065 -0.2794)
			(end -0.12065 -0.3048)
			(stroke
				(width 0.1)
				(type default)
			)
			(layer "B.Fab")
		)
		(fp_line
			(start -0.12065 -0.3048)
			(end -0.67945 -0.3048)
			(stroke
				(width 0.1)
				(type default)
			)
			(layer "B.Fab")
		)
		(fp_line
			(start -0.67945 0.3048)
			(end -0.120396 0.3048)
			(stroke
				(width 0.1)
				(type default)
			)
			(layer "B.Fab")
		)
		(fp_line
			(start -0.67945 -0.3048)
			(end -0.67945 0.3048)
			(stroke
				(width 0.1)
				(type default)
			)
			(layer "B.Fab")
		)
		(pad "1" smd circle
			(at 0.40005 0)
			(size 0 0)
			(layers "B.Cu" "B.Mask" "B.Paste")
			(net "P3V3")
		)
		(pad "2" smd circle
			(at -0.40005 0)
			(size 0 0)
			(layers "B.Cu" "B.Mask" "B.Paste")
			(net "FM_SMB_PEHPCPU0_PCIE_ALERT_R_N")
		)
	)
	(footprint ""
		(layer "B.Cu")
		(at 362.380276 -333.73568 90)
		(property "Reference" "PC281_P0_3"
			(at 0 0 90)
			(layer "B.SilkS")
			(hide yes)
			(effects
				(font
					(size 1.27 1.27)
				)
				(justify mirror)
			)
		)
		(property "Value" ""
			(at 0 0 90)
			(layer "B.Fab")
			(effects
				(font
					(size 1.27 1.27)
				)
				(justify mirror)
			)
		)
		(duplicate_pad_numbers_are_jumpers no)
		(fp_line
			(start 1.524 -0.762)
			(end -1.524 -0.762)
			(stroke
				(width 0.1524)
				(type default)
			)
			(layer "B.SilkS")
		)
		(fp_line
			(start -1.524 -0.762)
			(end -1.524 0.762)
			(stroke
				(width 0.1524)
				(type default)
			)
			(layer "B.SilkS")
		)
		(fp_line
			(start 1.524 0.762)
			(end 1.524 -0.762)
			(stroke
				(width 0.1524)
				(type default)
			)
			(layer "B.SilkS")
		)
		(fp_line
			(start -1.524 0.762)
			(end 1.524 0.762)
			(stroke
				(width 0.1524)
				(type default)
			)
			(layer "B.SilkS")
		)
		(fp_line
			(start 1.1049 -0.724916)
			(end 1.1049 0.724916)
			(stroke
				(width 0.1)
				(type default)
			)
			(layer "B.Fab")
		)
		(fp_line
			(start -1.1049 -0.724916)
			(end 1.1049 -0.724916)
			(stroke
				(width 0.1)
				(type default)
			)
			(layer "B.Fab")
		)
		(fp_line
			(start 1.1049 0.724916)
			(end -1.1049 0.724916)
			(stroke
				(width 0.1)
				(type default)
			)
			(layer "B.Fab")
		)
		(fp_line
			(start -1.1049 0.724916)
			(end -1.1049 -0.724916)
			(stroke
				(width 0.1)
				(type default)
			)
			(layer "B.Fab")
		)
		(pad "1" smd rect
			(at 0.889 0 90)
			(size 1.016 1.27)
			(layers "B.Cu" "B.Mask" "B.Paste")
			(net "SW_P12V_PVCCIN_CPU0_FLT")
		)
		(pad "2" smd rect
			(at -0.889 0 90)
			(size 1.016 1.27)
			(layers "B.Cu" "B.Mask" "B.Paste")
			(net "GND")
		)
	)
)
